# S9S_MB_2U (Grand Teton) — schematic netlist excerpt (pin names and nets, part order shuffled) for the footprints in the layout excerpt that follows; sources: Cadence DE-HDL packaged netlist, KiCad conversion of 03242023_DA0F0TMBIJ0_F0T_Motherboard_J_brd_V01_OCP.brd

PC208  Q_CAPP  270UF 16V 20% OSCON  pkg THLF  page 275 : A = SW_P12V_PVCCINFAON_CPU0_FLT ; B = GND

U315  PCA9617ADP  IC  pkg TSSOP8_3XB  page 237
  VCCA  = P3V3_AUX
  SCLA  = SMB_HOST_CLK_BUF_3V3AUX_SCL
  SDAA  = SMB_HOST_CLK_BUF_3V3AUX_SDA
  GND  = GND
  EN  = PU_CLK_BUF_ISO_EN
  SDAB  = SMB_HOST_CLK_BUF_ISO_3V3AUX_S_2
  SCLB  = SMB_HOST_CLK_BUF_ISO_3V3AUX_S_1
  VCCB  = P3V3

(kicad_pcb
	(version 20260206)
	(generator "pcbnew")
	(generator_version "10.0")
	(general
		(thickness 1.6)
		(legacy_teardrops no)
	)
	(paper "A4")
	(title_block
		(title "03242023_DA0F0TMBIJ0_F0T_Motherboard_J_brd_V01_OCP.brd")
		(comment 1 "Grand Teton / footprints 3720-3721 of 6105")
	)
	(layers
		(0 "F.Cu" signal "TOP")
		(4 "In1.Cu" signal "GND")
		(6 "In2.Cu" signal "IN1")
		(8 "In3.Cu" signal "GND1")
		(10 "In4.Cu" signal "IN2")
		(12 "In5.Cu" signal "GND2")
		(14 "In6.Cu" signal "IN3")
		(16 "In7.Cu" signal "GND3")
		(18 "In8.Cu" signal "VCC")
		(20 "In9.Cu" signal "VCC1")
		(22 "In10.Cu" signal "GND4")
		(24 "In11.Cu" signal "IN4")
		(26 "In12.Cu" signal "GND5")
		(28 "In13.Cu" signal "IN5")
		(30 "In14.Cu" signal "GND6")
		(32 "In15.Cu" signal "IN6")
		(34 "In16.Cu" signal "GND7")
		(2 "B.Cu" signal "BOTTOM")
		(9 "F.Adhes" user "F.Adhesive")
		(11 "B.Adhes" user "B.Adhesive")
		(13 "F.Paste" user "Package Geometry/Pastemask Top")
		(15 "B.Paste" user "Package Geometry/Pastemask Bottom")
		(5 "F.SilkS" user "Ref Des/Silkscreen Top")
		(7 "B.SilkS" user "Ref Des/Silkscreen Bottom")
		(1 "F.Mask" user "Board Geometry/Soldermask Top")
		(3 "B.Mask" user "Board Geometry/Soldermask Bottom")
		(17 "Dwgs.User" user "User.Drawings")
		(19 "Cmts.User" user "User.Comments")
		(21 "Eco1.User" user "User.Eco1")
		(23 "Eco2.User" user "User.Eco2")
		(25 "Edge.Cuts" user "Board Geometry/Outline")
		(27 "Margin" user)
		(31 "F.CrtYd" user "Package Geometry/Place Bound Top")
		(29 "B.CrtYd" user "Package Geometry/Place Bound Bottom")
		(35 "F.Fab" user "Ref Des/Assembly Top")
		(33 "B.Fab" user "Ref Des/Assembly Bottom")
	)
	(footprint ""
		(layer "F.Cu")
		(at 427.452028 -159.516318)
		(property "Reference" "PC208"
			(at 0 0 0)
			(layer "F.SilkS")
			(hide yes)
			(effects
				(font
					(size 1.27 1.27)
				)
			)
		)
		(property "Value" ""
			(at 0 0 0)
			(layer "F.Fab")
			(effects
				(font
					(size 1.27 1.27)
				)
			)
		)
		(duplicate_pad_numbers_are_jumpers no)
		(fp_line
			(start -3.400044 1.249934)
			(end 3.400044 1.249934)
			(stroke
				(width 0.1524)
				(type default)
			)
			(layer "F.SilkS")
		)
		(fp_circle
			(center 0 1.249934)
			(end 3.400044 1.249934)
			(stroke
				(width 0.1524)
				(type default)
			)
			(fill no)
			(layer "F.SilkS")
		)
		(fp_poly
			(pts
				(arc
					(start -3.400044 1.249934)
					(mid 0 4.649978)
					(end 3.400044 1.249934)
				)
			)
			(stroke
				(width 0)
				(type default)
			)
			(fill yes)
			(layer "F.SilkS")
		)
		(fp_circle
			(center 0 1.249934)
			(end 3.400044 1.249934)
			(stroke
				(width 0.1)
				(type default)
			)
			(fill no)
			(layer "F.Fab")
		)
		(pad "1" thru_hole rect
			(at 0 0)
			(size 1.524 1.524)
			(drill 1.016)
			(layers "*.Cu" "*.Mask")
			(remove_unused_layers no)
			(net "SW_P12V_PVCCINFAON_CPU0_FLT")
			(clearance 0)
			(padstack
				(mode front_inner_back)
				(layer "Inner"
					(shape circle)
					(size 1.524 1.524)
					(clearance 0)
				)
				(layer "B.Cu"
					(shape rect)
					(size 1.524 1.524)
					(clearance 0)
				)
			)
		)
		(pad "2" thru_hole circle
			(at 0 2.500122)
			(size 1.524 1.524)
			(drill 1.016)
			(layers "*.Cu" "*.Mask")
			(remove_unused_layers no)
			(net "GND")
			(clearance 0)
		)
	)
	(footprint ""
		(layer "F.Cu")
		(at 268.668246 -130.536696 180)
		(property "Reference" "U315"
			(at 1.132332 2.691892 0)
			(unlocked yes)
			(layer "F.SilkS")
			(effects
				(font
					(size 0.7874 0.5842)
					(thickness 0.1524)
				)
				(justify left)
			)
		)
		(property "Value" ""
			(at 0 0 180)
			(layer "F.Fab")
			(effects
				(font
					(size 1.27 1.27)
				)
			)
		)
		(duplicate_pad_numbers_are_jumpers no)
		(fp_line
			(start 1.463548 1.549908)
			(end -1.463548 1.549908)
			(stroke
				(width 0.1524)
				(type default)
			)
			(layer "F.SilkS")
		)
		(fp_line
			(start 1.463548 -1.549908)
			(end 1.463548 1.549908)
			(stroke
				(width 0.1524)
				(type default)
			)
			(layer "F.SilkS")
		)
		(fp_line
			(start 0.762 -1.549908)
			(end 1.463548 -1.549908)
			(stroke
				(width 0.1524)
				(type default)
			)
			(layer "F.SilkS")
		)
		(fp_line
			(start 0 -0.762)
			(end 0.762 -1.549908)
			(stroke
				(width 0.1524)
				(type default)
			)
			(layer "F.SilkS")
		)
		(fp_line
			(start -0.787908 -1.549908)
			(end 0 -0.762)
			(stroke
				(width 0.1524)
				(type default)
			)
			(layer "F.SilkS")
		)
		(fp_line
			(start -1.463548 1.549908)
			(end -1.463548 -1.549908)
			(stroke
				(width 0.1524)
				(type default)
			)
			(layer "F.SilkS")
		)
		(fp_line
			(start -1.463548 -1.549908)
			(end -0.787908 -1.549908)
			(stroke
				(width 0.1524)
				(type default)
			)
			(layer "F.SilkS")
		)
		(fp_poly
			(pts
				(xy -2.86004 -1.050036) (xy -3.4798 -0.740156) (xy -3.4798 -1.359916)
			)
			(stroke
				(width 0)
				(type default)
			)
			(fill yes)
			(layer "F.SilkS")
		)
		(fp_line
			(start 1.549908 1.549908)
			(end -1.549908 1.549908)
			(stroke
				(width 0.1)
				(type default)
			)
			(layer "F.Fab")
		)
		(fp_line
			(start 1.549908 -1.549908)
			(end 1.549908 1.549908)
			(stroke
				(width 0.1)
				(type default)
			)
			(layer "F.Fab")
		)
		(fp_line
			(start -1.549908 1.549908)
			(end -1.549908 -1.549908)
			(stroke
				(width 0.1)
				(type default)
			)
			(layer "F.Fab")
		)
		(fp_line
			(start -1.549908 -1.549908)
			(end 1.549908 -1.549908)
			(stroke
				(width 0.1)
				(type default)
			)
			(layer "F.Fab")
		)
		(fp_poly
			(pts
				(xy -3.4798 -1.359916) (xy -2.86004 -1.050036) (xy -3.4798 -0.740156)
			)
			(stroke
				(width 0)
				(type default)
			)
			(fill yes)
			(layer "F.Fab")
		)
		(pad "1" smd rect
			(at -2.175002 -1.050036 270)
			(size 0.6096 1.1684)
			(layers "F.Cu" "F.Mask" "F.Paste")
			(net "P3V3_AUX")
		)
		(pad "2" smd rect
			(at -2.175002 -0.32512 270)
			(size 0.4318 1.1684)
			(layers "F.Cu" "F.Mask" "F.Paste")
			(net "SMB_HOST_CLK_BUF_3V3AUX_SCL")
		)
		(pad "3" smd rect
			(at -2.175002 0.32512 270)
			(size 0.4318 1.1684)
			(layers "F.Cu" "F.Mask" "F.Paste")
			(net "SMB_HOST_CLK_BUF_3V3AUX_SDA")
		)
		(pad "4" smd rect
			(at -2.175002 1.050036 270)
			(size 0.6096 1.1684)
			(layers "F.Cu" "F.Mask" "F.Paste")
			(net "GND")
		)
		(pad "5" smd rect
			(at 2.175002 1.050036 270)
			(size 0.6096 1.1684)
			(layers "F.Cu" "F.Mask" "F.Paste")
			(net "PU_CLK_BUF_ISO_EN")
		)
		(pad "6" smd rect
			(at 2.175002 0.32512 270)
			(size 0.4318 1.1684)
			(layers "F.Cu" "F.Mask" "F.Paste")
			(net "SMB_HOST_CLK_BUF_ISO_3V3AUX_S_2")
		)
		(pad "7" smd rect
			(at 2.175002 -0.32512 270)
			(size 0.4318 1.1684)
			(layers "F.Cu" "F.Mask" "F.Paste")
			(net "SMB_HOST_CLK_BUF_ISO_3V3AUX_S_1")
		)
		(pad "8" smd rect
			(at 2.175002 -1.050036 270)
			(size 0.6096 1.1684)
			(layers "F.Cu" "F.Mask" "F.Paste")
			(net "P3V3")
		)
	)
)
